FILE_TYPE = MACRO_DRAWING;
SET COLOR_WIRE YELLOW;
SET COLOR_PROP ORANGE;
SET COLOR_DOT WHITE;
SET COLOR_ARC YELLOW;
SET COLOR_BODY GREEN;
SET COLOR_NOTE PURPLE;
SET PROP_DISPLAY VALUE;
SET PAGE_NUMBER P13;
FORCEADD OFFPAGE..1
(-2250 2925);
FORCEPROP 2 LAST $XR0 209 
J 0
(-2532 2925);
DISPLAY 0.638298 (-2532 2925);
PAINT MONO (-2532 2925);
FORCEPROP 2 LAST CDS_LIB standard
J 0
(-2250 2925);
DISPLAY INVISIBLE (-2250 2925);
FORCEPROP 1 LAST OFFPAGE TRUE
J 0
(-1925 2800);
DISPLAY 0.872340 (-1925 2800);
DISPLAY INVISIBLE (-1925 2800);
FORCEPROP 1 LAST COMMENT_BODY TRUE
J 0
(-2125 2825);
DISPLAY 0.872340 (-2125 2825);
PAINT GREEN (-2125 2825);
DISPLAY INVISIBLE (-2125 2825);
FORCEPROP 2 LAST PATH I10
J 0
(-2525 2975);
DISPLAY 1.021277 (-2525 2975);
DISPLAY INVISIBLE (-2525 2975);
FORCEADD OFFPAGE..1
(-2250 2975);
FORCEPROP 2 LAST $XR0 209 
J 0
(-2532 2975);
DISPLAY 0.638298 (-2532 2975);
PAINT MONO (-2532 2975);
FORCEPROP 2 LAST CDS_LIB standard
J 0
(-2250 2975);
DISPLAY INVISIBLE (-2250 2975);
FORCEPROP 1 LAST OFFPAGE TRUE
J 0
(-1925 2850);
DISPLAY 0.872340 (-1925 2850);
DISPLAY INVISIBLE (-1925 2850);
FORCEPROP 1 LAST COMMENT_BODY TRUE
J 0
(-2125 2875);
DISPLAY 0.872340 (-2125 2875);
PAINT GREEN (-2125 2875);
DISPLAY INVISIBLE (-2125 2875);
FORCEPROP 2 LAST PATH I11
J 0
(-2525 3025);
DISPLAY 1.021277 (-2525 3025);
DISPLAY INVISIBLE (-2525 3025);
FORCEADD OFFPAGE..3
R 2
(-2250 2325);
FORCEPROP 2 LAST $XR0 229 
J 0
(-2560 2325);
DISPLAY 0.638298 (-2560 2325);
PAINT MONO (-2560 2325);
FORCEPROP 2 LAST CDS_LIB standard
J 0
(-2250 2325);
DISPLAY INVISIBLE (-2250 2325);
FORCEPROP 1 LAST OFFPAGE TRUE
J 2
(-2575 2200);
DISPLAY 0.872340 (-2575 2200);
DISPLAY INVISIBLE (-2575 2200);
FORCEPROP 1 LAST COMMENT_BODY TRUE
J 2
(-2200 2225);
DISPLAY 0.872340 (-2200 2225);
PAINT GREEN (-2200 2225);
DISPLAY INVISIBLE (-2200 2225);
FORCEPROP 2 LAST PATH I12
J 0
(-2550 2375);
DISPLAY 1.021277 (-2550 2375);
DISPLAY INVISIBLE (-2550 2375);
FORCEADD OFFPAGE..2
R 2
(-2250 2375);
FORCEPROP 2 LAST $XR0 229 
J 0
(-2505 2375);
DISPLAY 0.638298 (-2505 2375);
PAINT MONO (-2505 2375);
FORCEPROP 2 LAST CDS_LIB standard
J 0
(-2250 2375);
DISPLAY INVISIBLE (-2250 2375);
FORCEPROP 1 LAST OFFPAGE TRUE
J 2
(-2575 2250);
DISPLAY 0.872340 (-2575 2250);
DISPLAY INVISIBLE (-2575 2250);
FORCEPROP 1 LAST COMMENT_BODY TRUE
J 2
(-2205 2280);
DISPLAY 0.872340 (-2205 2280);
PAINT GREEN (-2205 2280);
DISPLAY INVISIBLE (-2205 2280);
FORCEPROP 2 LAST PATH I13
J 0
(-2525 2425);
DISPLAY 1.021277 (-2525 2425);
DISPLAY INVISIBLE (-2525 2425);
FORCEADD OFFPAGE..3
R 2
(-2250 2175);
FORCEPROP 2 LAST $XR0 229 
J 0
(-2560 2175);
DISPLAY 0.638298 (-2560 2175);
PAINT MONO (-2560 2175);
FORCEPROP 2 LAST CDS_LIB standard
J 0
(-2250 2175);
DISPLAY INVISIBLE (-2250 2175);
FORCEPROP 1 LAST OFFPAGE TRUE
J 2
(-2575 2050);
DISPLAY 0.872340 (-2575 2050);
DISPLAY INVISIBLE (-2575 2050);
FORCEPROP 1 LAST COMMENT_BODY TRUE
J 2
(-2200 2075);
DISPLAY 0.872340 (-2200 2075);
PAINT GREEN (-2200 2075);
DISPLAY INVISIBLE (-2200 2075);
FORCEPROP 2 LAST PATH I14
J 0
(-2550 2225);
DISPLAY 1.021277 (-2550 2225);
DISPLAY INVISIBLE (-2550 2225);
FORCEADD OFFPAGE..2
R 2
(-2250 2225);
FORCEPROP 2 LAST $XR0 229 
J 0
(-2505 2225);
DISPLAY 0.638298 (-2505 2225);
PAINT MONO (-2505 2225);
FORCEPROP 2 LAST CDS_LIB standard
J 0
(-2250 2225);
DISPLAY INVISIBLE (-2250 2225);
FORCEPROP 1 LAST OFFPAGE TRUE
J 2
(-2575 2100);
DISPLAY 0.872340 (-2575 2100);
DISPLAY INVISIBLE (-2575 2100);
FORCEPROP 1 LAST COMMENT_BODY TRUE
J 2
(-2205 2130);
DISPLAY 0.872340 (-2205 2130);
PAINT GREEN (-2205 2130);
DISPLAY INVISIBLE (-2205 2130);
FORCEPROP 2 LAST PATH I15
J 0
(-2525 2275);
DISPLAY 1.021277 (-2525 2275);
DISPLAY INVISIBLE (-2525 2275);
FORCEADD Q_RES..1
(-2125 2025);
FORCEPROP 1 LAST PART_NUMBER CS11002FB07
J 0
(-2000 2000);
DISPLAY 0.404255 (-2000 2000);
DISPLAY INVISIBLE (-2000 2000);
FORCEPROP 1 LAST MATERIAL CHIP
J 0
(-2000 1975);
DISPLAY 0.404255 (-2000 1975);
FORCEPROP 1 LAST WATTAGE 1/16W
J 2
(-1700 1975);
DISPLAY 0.404255 (-1700 1975);
FORCEPROP 1 LAST TOLERANCE 1%
J 0
(-1900 2025);
DISPLAY 0.510638 (-1900 2025);
FORCEPROP 1 LAST PACK_TYPE 0402LF
J 0
(-1800 2025);
DISPLAY 0.510638 (-1800 2025);
FORCEPROP 1 LAST VALUE 100
J 2
(-1925 2025);
DISPLAY 0.510638 (-1925 2025);
FORCEPROP 1 LAST $LOCATION R2
J 0
(-2300 2025);
DISPLAY 0.638298 (-2300 2025);
FORCEPROP 1 LASTPIN (-2225 2025) $PN 1
J 0
(-2213 2037);
DISPLAY 0.787234 (-2213 2037);
FORCEPROP 1 LASTPIN (-2025 2025) $PN 2
J 0
(-2063 2037);
DISPLAY 0.787234 (-2063 2037);
FORCEPROP 2 LAST CDS_LIB pure_quanta
J 0
(-2125 2025);
PAINT MONO (-2125 2025);
DISPLAY INVISIBLE (-2125 2025);
FORCEPROP 1 LAST $LOCATION R2
J 0
(-2175 2225);
DISPLAY 1.021277 (-2175 2225);
DISPLAY INVISIBLE (-2175 2225);
FORCEPROP 2 LAST CDS_LOCATION R2
J 0
(-2175 2225);
DISPLAY 1.021277 (-2175 2225);
DISPLAY INVISIBLE (-2175 2225);
FORCEPROP 2 LAST $SEC 1
J 0
(-2175 2225);
DISPLAY 0.680851 (-2175 2225);
PAINT MONO (-2175 2225);
DISPLAY INVISIBLE (-2175 2225);
FORCEPROP 2 LAST CDS_SEC 1
J 0
(-2175 2225);
DISPLAY 1.021277 (-2175 2225);
DISPLAY INVISIBLE (-2175 2225);
FORCEPROP 1 LAST PATH I16
J 0
(-2175 2175);
DISPLAY 0.978723 (-2175 2175);
PAINT WHITE (-2175 2175);
DISPLAY INVISIBLE (-2175 2175);
FORCEADD OFFPAGE..1
(-3250 2025);
FORCEPROP 2 LAST $XR1 44 
J 0
(-3622 2025);
DISPLAY 0.638298 (-3622 2025);
PAINT MONO (-3622 2025);
FORCEPROP 2 LAST $XR0 132 
J 0
(-3532 2025);
DISPLAY 0.638298 (-3532 2025);
PAINT MONO (-3532 2025);
FORCEPROP 2 LAST CDS_LIB standard
J 0
(-3250 2025);
PAINT MONO (-3250 2025);
DISPLAY INVISIBLE (-3250 2025);
FORCEPROP 1 LAST OFFPAGE TRUE
J 0
(-2925 1900);
DISPLAY 0.872340 (-2925 1900);
DISPLAY INVISIBLE (-2925 1900);
FORCEPROP 1 LAST COMMENT_BODY TRUE
J 0
(-3125 1925);
DISPLAY 0.872340 (-3125 1925);
PAINT GREEN (-3125 1925);
DISPLAY INVISIBLE (-3125 1925);
FORCEPROP 2 LAST PATH I17
J 0
(-3525 2075);
DISPLAY 1.021277 (-3525 2075);
DISPLAY INVISIBLE (-3525 2075);
FORCEADD Q_RES..1
(-2125 2075);
FORCEPROP 1 LAST PART_NUMBER CS01002FB07
J 0
(-2000 2100);
DISPLAY 0.404255 (-2000 2100);
DISPLAY INVISIBLE (-2000 2100);
FORCEPROP 1 LAST WATTAGE 1/16W
J 2
(-1700 2125);
DISPLAY 0.404255 (-1700 2125);
FORCEPROP 1 LAST TOLERANCE 1%
J 0
(-1900 2075);
DISPLAY 0.510638 (-1900 2075);
FORCEPROP 1 LAST VALUE 10
J 2
(-1950 2075);
DISPLAY 0.510638 (-1950 2075);
FORCEPROP 1 LAST MATERIAL CHIP
J 0
(-2000 2125);
DISPLAY 0.404255 (-2000 2125);
FORCEPROP 1 LAST PACK_TYPE 0402LF
J 0
(-1800 2075);
DISPLAY 0.510638 (-1800 2075);
FORCEPROP 1 LAST $LOCATION R1
J 0
(-2300 2075);
DISPLAY 0.638298 (-2300 2075);
FORCEPROP 1 LASTPIN (-2225 2075) $PN 1
J 0
(-2213 2087);
DISPLAY 0.787234 (-2213 2087);
FORCEPROP 1 LASTPIN (-2025 2075) $PN 2
J 0
(-2063 2087);
DISPLAY 0.787234 (-2063 2087);
FORCEPROP 2 LAST CDS_LIB pure_quanta
J 0
(-2125 2075);
PAINT MONO (-2125 2075);
DISPLAY INVISIBLE (-2125 2075);
FORCEPROP 1 LAST $LOCATION R1
J 0
(-2175 2275);
DISPLAY 1.021277 (-2175 2275);
DISPLAY INVISIBLE (-2175 2275);
FORCEPROP 2 LAST CDS_LOCATION R1
J 0
(-2175 2275);
DISPLAY 1.021277 (-2175 2275);
DISPLAY INVISIBLE (-2175 2275);
FORCEPROP 2 LAST $SEC 1
J 0
(-2175 2275);
DISPLAY 0.680851 (-2175 2275);
PAINT MONO (-2175 2275);
DISPLAY INVISIBLE (-2175 2275);
FORCEPROP 2 LAST CDS_SEC 1
J 0
(-2175 2275);
DISPLAY 1.021277 (-2175 2275);
DISPLAY INVISIBLE (-2175 2275);
FORCEPROP 1 LAST PATH I18
J 0
(-2175 2225);
DISPLAY 0.978723 (-2175 2225);
PAINT WHITE (-2175 2225);
DISPLAY INVISIBLE (-2175 2225);
FORCEADD OFFPAGE..2
R 2
(-3250 2075);
FORCEPROP 2 LAST $XR1 132 
J 0
(-3594 2075);
DISPLAY 0.638298 (-3594 2075);
PAINT MONO (-3594 2075);
FORCEPROP 2 LAST $XR0 44 
J 0
(-3474 2075);
DISPLAY 0.638298 (-3474 2075);
PAINT MONO (-3474 2075);
FORCEPROP 2 LAST CDS_LIB standard
J 0
(-3250 2075);
PAINT MONO (-3250 2075);
DISPLAY INVISIBLE (-3250 2075);
FORCEPROP 1 LAST OFFPAGE TRUE
J 2
(-3575 1950);
DISPLAY 0.872340 (-3575 1950);
DISPLAY INVISIBLE (-3575 1950);
FORCEPROP 1 LAST COMMENT_BODY TRUE
J 2
(-3205 1980);
DISPLAY 0.872340 (-3205 1980);
PAINT GREEN (-3205 1980);
DISPLAY INVISIBLE (-3205 1980);
FORCEPROP 2 LAST PATH I19
J 0
(-3525 2125);
DISPLAY 1.021277 (-3525 2125);
DISPLAY INVISIBLE (-3525 2125);
FORCEADD OFFPAGE..1
(-2250 3275);
FORCEPROP 2 LAST $XR0 206 
J 0
(-2532 3275);
DISPLAY 0.638298 (-2532 3275);
PAINT MONO (-2532 3275);
FORCEPROP 2 LAST CDS_LIB standard
J 0
(-2250 3275);
DISPLAY INVISIBLE (-2250 3275);
FORCEPROP 1 LAST OFFPAGE TRUE
J 0
(-1925 3150);
DISPLAY 0.872340 (-1925 3150);
DISPLAY INVISIBLE (-1925 3150);
FORCEPROP 1 LAST COMMENT_BODY TRUE
J 0
(-2125 3175);
DISPLAY 0.872340 (-2125 3175);
PAINT GREEN (-2125 3175);
DISPLAY INVISIBLE (-2125 3175);
FORCEPROP 2 LAST PATH I2
J 0
(-2525 3325);
DISPLAY 1.021277 (-2525 3325);
DISPLAY INVISIBLE (-2525 3325);
FORCEADD Q_RES..1
(-2125 1925);
FORCEPROP 1 LAST PART_NUMBER CS03322FB03
J 0
(-2000 1900);
DISPLAY 0.404255 (-2000 1900);
DISPLAY INVISIBLE (-2000 1900);
FORCEPROP 1 LAST PACK_TYPE 0402LF
J 0
(-1800 1925);
DISPLAY 0.510638 (-1800 1925);
FORCEPROP 1 LAST WATTAGE 1/16W
J 2
(-1675 1900);
DISPLAY 0.404255 (-1675 1900);
FORCEPROP 1 LAST TOLERANCE 1%
J 0
(-1900 1925);
DISPLAY 0.510638 (-1900 1925);
FORCEPROP 1 LAST MATERIAL CHIP
J 0
(-1650 1900);
DISPLAY 0.404255 (-1650 1900);
FORCEPROP 1 LAST VALUE 33.2
J 2
(-1925 1925);
DISPLAY 0.510638 (-1925 1925);
FORCEPROP 1 LAST $LOCATION R3
J 0
(-2300 1925);
DISPLAY 0.638298 (-2300 1925);
FORCEPROP 1 LASTPIN (-2225 1925) $PN 1
J 0
(-2213 1937);
DISPLAY 0.787234 (-2213 1937);
FORCEPROP 1 LASTPIN (-2025 1925) $PN 2
J 0
(-2063 1937);
DISPLAY 0.787234 (-2063 1937);
FORCEPROP 2 LAST CDS_LIB pure_quanta
J 0
(-2125 1925);
PAINT MONO (-2125 1925);
DISPLAY INVISIBLE (-2125 1925);
FORCEPROP 1 LAST $LOCATION R3
J 0
(-2175 2125);
DISPLAY 1.021277 (-2175 2125);
DISPLAY INVISIBLE (-2175 2125);
FORCEPROP 2 LAST CDS_LOCATION R3
J 0
(-2175 2125);
DISPLAY 1.021277 (-2175 2125);
DISPLAY INVISIBLE (-2175 2125);
FORCEPROP 2 LAST $SEC 1
J 0
(-2175 2125);
DISPLAY 0.680851 (-2175 2125);
PAINT MONO (-2175 2125);
DISPLAY INVISIBLE (-2175 2125);
FORCEPROP 2 LAST CDS_SEC 1
J 0
(-2175 2125);
DISPLAY 1.021277 (-2175 2125);
DISPLAY INVISIBLE (-2175 2125);
FORCEPROP 1 LAST PATH I21
J 0
(-2175 2075);
DISPLAY 0.978723 (-2175 2075);
PAINT WHITE (-2175 2075);
DISPLAY INVISIBLE (-2175 2075);
FORCEADD OFFPAGE..3
R 2
(-3250 1925);
FORCEPROP 2 LAST $XR1 197 
J 0
(-3649 1925);
DISPLAY 0.638298 (-3649 1925);
PAINT MONO (-3649 1925);
FORCEPROP 2 LAST $XR0 44 
J 0
(-3529 1925);
DISPLAY 0.638298 (-3529 1925);
PAINT MONO (-3529 1925);
FORCEPROP 2 LAST CDS_LIB standard
J 0
(-3250 1925);
PAINT MONO (-3250 1925);
DISPLAY INVISIBLE (-3250 1925);
FORCEPROP 1 LAST OFFPAGE TRUE
J 2
(-3575 1800);
DISPLAY 0.872340 (-3575 1800);
DISPLAY INVISIBLE (-3575 1800);
FORCEPROP 1 LAST COMMENT_BODY TRUE
J 2
(-3200 1825);
DISPLAY 0.872340 (-3200 1825);
PAINT GREEN (-3200 1825);
DISPLAY INVISIBLE (-3200 1825);
FORCEPROP 2 LAST PATH I22
J 0
(-3200 2000);
DISPLAY 1.021277 (-3200 2000);
DISPLAY INVISIBLE (-3200 2000);
FORCEADD OFFPAGE..1
(-3250 1775);
FORCEPROP 2 LAST $XR3 44 
J 0
(-3862 1775);
DISPLAY 0.638298 (-3862 1775);
PAINT MONO (-3862 1775);
FORCEPROP 2 LAST $XR2 182 
J 0
(-3772 1775);
DISPLAY 0.638298 (-3772 1775);
PAINT MONO (-3772 1775);
FORCEPROP 2 LAST $XR1 134 
J 0
(-3652 1775);
DISPLAY 0.638298 (-3652 1775);
PAINT MONO (-3652 1775);
FORCEPROP 2 LAST $XR0 131 
J 0
(-3532 1775);
DISPLAY 0.638298 (-3532 1775);
PAINT MONO (-3532 1775);
FORCEPROP 2 LAST CDS_LIB standard
J 0
(-3250 1775);
PAINT MONO (-3250 1775);
DISPLAY INVISIBLE (-3250 1775);
FORCEPROP 1 LAST OFFPAGE TRUE
J 0
(-2925 1650);
DISPLAY 0.872340 (-2925 1650);
DISPLAY INVISIBLE (-2925 1650);
FORCEPROP 1 LAST COMMENT_BODY TRUE
J 0
(-3125 1675);
DISPLAY 0.872340 (-3125 1675);
PAINT GREEN (-3125 1675);
DISPLAY INVISIBLE (-3125 1675);
FORCEPROP 2 LAST PATH I23
J 0
(-3200 1850);
DISPLAY 1.021277 (-3200 1850);
DISPLAY INVISIBLE (-3200 1850);
FORCEADD Q_RES..1
(-2125 1775);
FORCEPROP 1 LAST PART_NUMBER CS11002FB07
J 0
(-2200 1725);
DISPLAY 0.404255 (-2200 1725);
DISPLAY INVISIBLE (-2200 1725);
FORCEPROP 1 LAST PACK_TYPE 0402LF
J 0
(-1800 1775);
DISPLAY 0.510638 (-1800 1775);
FORCEPROP 1 LAST TOLERANCE 1%
J 0
(-1900 1775);
DISPLAY 0.510638 (-1900 1775);
FORCEPROP 1 LAST VALUE 100
J 2
(-1925 1775);
DISPLAY 0.510638 (-1925 1775);
FORCEPROP 1 LAST $LOCATION R5
J 0
(-2300 1775);
DISPLAY 0.638298 (-2300 1775);
FORCEPROP 1 LASTPIN (-2225 1775) $PN 1
J 0
(-2213 1787);
DISPLAY 0.787234 (-2213 1787);
FORCEPROP 1 LASTPIN (-2025 1775) $PN 2
J 0
(-2063 1787);
DISPLAY 0.787234 (-2063 1787);
FORCEPROP 2 LAST CDS_LIB pure_quanta
J 0
(-2125 1775);
PAINT MONO (-2125 1775);
DISPLAY INVISIBLE (-2125 1775);
FORCEPROP 1 LAST MATERIAL CHIP
J 0
(-1975 1725);
DISPLAY 0.404255 (-1975 1725);
DISPLAY INVISIBLE (-1975 1725);
FORCEPROP 1 LAST WATTAGE 1/16W
J 2
(-1775 1725);
DISPLAY 0.404255 (-1775 1725);
DISPLAY INVISIBLE (-1775 1725);
FORCEPROP 1 LAST $LOCATION R5
J 0
(-2175 1975);
DISPLAY 1.021277 (-2175 1975);
DISPLAY INVISIBLE (-2175 1975);
FORCEPROP 2 LAST CDS_LOCATION R5
J 0
(-2175 1975);
DISPLAY 1.021277 (-2175 1975);
DISPLAY INVISIBLE (-2175 1975);
FORCEPROP 2 LAST $SEC 1
J 0
(-2175 1975);
DISPLAY 0.680851 (-2175 1975);
PAINT MONO (-2175 1975);
DISPLAY INVISIBLE (-2175 1975);
FORCEPROP 2 LAST CDS_SEC 1
J 0
(-2175 1975);
DISPLAY 1.021277 (-2175 1975);
DISPLAY INVISIBLE (-2175 1975);
FORCEPROP 1 LAST PATH I24
J 0
(-2175 1925);
DISPLAY 0.978723 (-2175 1925);
PAINT WHITE (-2175 1925);
DISPLAY INVISIBLE (-2175 1925);
FORCEADD Q_RES..1
(-2125 1725);
FORCEPROP 1 LAST PART_NUMBER CS11002FB07
J 0
(-2000 1700);
DISPLAY 0.404255 (-2000 1700);
DISPLAY INVISIBLE (-2000 1700);
FORCEPROP 1 LAST MATERIAL CHIP
J 0
(-2000 1675);
DISPLAY 0.404255 (-2000 1675);
FORCEPROP 1 LAST WATTAGE 1/16W
J 2
(-1700 1675);
DISPLAY 0.404255 (-1700 1675);
FORCEPROP 1 LAST VALUE 100
J 2
(-1925 1725);
DISPLAY 0.510638 (-1925 1725);
FORCEPROP 1 LAST TOLERANCE 1%
J 0
(-1900 1725);
DISPLAY 0.510638 (-1900 1725);
FORCEPROP 1 LAST PACK_TYPE 0402LF
J 0
(-1800 1725);
DISPLAY 0.510638 (-1800 1725);
FORCEPROP 1 LAST $LOCATION R6
J 0
(-2300 1725);
DISPLAY 0.638298 (-2300 1725);
FORCEPROP 1 LASTPIN (-2225 1725) $PN 1
J 0
(-2213 1737);
DISPLAY 0.787234 (-2213 1737);
FORCEPROP 1 LASTPIN (-2025 1725) $PN 2
J 0
(-2063 1737);
DISPLAY 0.787234 (-2063 1737);
FORCEPROP 2 LAST CDS_LIB pure_quanta
J 0
(-2125 1725);
PAINT MONO (-2125 1725);
DISPLAY INVISIBLE (-2125 1725);
FORCEPROP 1 LAST $LOCATION R6
J 0
(-2175 1925);
DISPLAY 1.021277 (-2175 1925);
DISPLAY INVISIBLE (-2175 1925);
FORCEPROP 2 LAST CDS_LOCATION R6
J 0
(-2175 1925);
DISPLAY 1.021277 (-2175 1925);
DISPLAY INVISIBLE (-2175 1925);
FORCEPROP 2 LAST $SEC 1
J 0
(-2175 1925);
DISPLAY 0.680851 (-2175 1925);
PAINT MONO (-2175 1925);
DISPLAY INVISIBLE (-2175 1925);
FORCEPROP 2 LAST CDS_SEC 1
J 0
(-2175 1925);
DISPLAY 1.021277 (-2175 1925);
DISPLAY INVISIBLE (-2175 1925);
FORCEPROP 1 LAST PATH I25
J 0
(-2175 1875);
DISPLAY 0.978723 (-2175 1875);
PAINT WHITE (-2175 1875);
DISPLAY INVISIBLE (-2175 1875);
FORCEADD OFFPAGE..1
(-3250 1725);
FORCEPROP 2 LAST $XR1 44 
J 0
(-3622 1725);
DISPLAY 0.638298 (-3622 1725);
PAINT MONO (-3622 1725);
FORCEPROP 2 LAST $XR0 132 
J 0
(-3532 1725);
DISPLAY 0.638298 (-3532 1725);
PAINT MONO (-3532 1725);
FORCEPROP 2 LAST CDS_LIB standard
J 0
(-3250 1725);
PAINT MONO (-3250 1725);
DISPLAY INVISIBLE (-3250 1725);
FORCEPROP 1 LAST OFFPAGE TRUE
J 0
(-2925 1600);
DISPLAY 0.872340 (-2925 1600);
DISPLAY INVISIBLE (-2925 1600);
FORCEPROP 1 LAST COMMENT_BODY TRUE
J 0
(-3125 1625);
DISPLAY 0.872340 (-3125 1625);
PAINT GREEN (-3125 1625);
DISPLAY INVISIBLE (-3125 1625);
FORCEPROP 2 LAST PATH I26
J 0
(-3200 1800);
DISPLAY 1.021277 (-3200 1800);
DISPLAY INVISIBLE (-3200 1800);
FORCEADD OFFPAGE..1
(-3250 1825);
FORCEPROP 2 LAST $XR0 133 
J 0
(-3532 1825);
DISPLAY 0.638298 (-3532 1825);
PAINT MONO (-3532 1825);
FORCEPROP 2 LAST CDS_LIB standard
J 0
(-3250 1825);
PAINT MONO (-3250 1825);
DISPLAY INVISIBLE (-3250 1825);
FORCEPROP 1 LAST OFFPAGE TRUE
J 0
(-2925 1700);
DISPLAY 0.872340 (-2925 1700);
DISPLAY INVISIBLE (-2925 1700);
FORCEPROP 1 LAST COMMENT_BODY TRUE
J 0
(-3125 1725);
DISPLAY 0.872340 (-3125 1725);
PAINT GREEN (-3125 1725);
DISPLAY INVISIBLE (-3125 1725);
FORCEPROP 2 LAST PATH I28
J 0
(-3200 1900);
DISPLAY 1.021277 (-3200 1900);
DISPLAY INVISIBLE (-3200 1900);
FORCEADD Q_RES..1
(-2125 1825);
FORCEPROP 1 LAST PART_NUMBER CS12002FB06
J 0
(-2000 1850);
DISPLAY 0.404255 (-2000 1850);
DISPLAY INVISIBLE (-2000 1850);
FORCEPROP 1 LAST PACK_TYPE 0402LF
J 0
(-1800 1825);
DISPLAY 0.510638 (-1800 1825);
FORCEPROP 1 LAST TOLERANCE 1%
J 0
(-1900 1825);
DISPLAY 0.510638 (-1900 1825);
FORCEPROP 1 LAST VALUE 200
J 2
(-1925 1825);
DISPLAY 0.510638 (-1925 1825);
FORCEPROP 1 LAST WATTAGE 1/16W
J 2
(-1675 1850);
DISPLAY 0.404255 (-1675 1850);
FORCEPROP 1 LAST MATERIAL CHIP
J 0
(-1650 1850);
DISPLAY 0.404255 (-1650 1850);
FORCEPROP 1 LAST $LOCATION R4
J 0
(-2300 1825);
DISPLAY 0.638298 (-2300 1825);
FORCEPROP 1 LASTPIN (-2225 1825) $PN 1
J 0
(-2213 1837);
DISPLAY 0.787234 (-2213 1837);
FORCEPROP 1 LASTPIN (-2025 1825) $PN 2
J 0
(-2063 1837);
DISPLAY 0.787234 (-2063 1837);
FORCEPROP 2 LAST CDS_LIB pure_quanta
J 0
(-2125 1825);
PAINT MONO (-2125 1825);
DISPLAY INVISIBLE (-2125 1825);
FORCEPROP 1 LAST $LOCATION R4
J 0
(-2175 2025);
DISPLAY 1.021277 (-2175 2025);
DISPLAY INVISIBLE (-2175 2025);
FORCEPROP 2 LAST CDS_LOCATION R4
J 0
(-2175 2025);
DISPLAY 1.021277 (-2175 2025);
DISPLAY INVISIBLE (-2175 2025);
FORCEPROP 2 LAST $SEC 1
J 0
(-2175 2025);
DISPLAY 0.680851 (-2175 2025);
PAINT MONO (-2175 2025);
DISPLAY INVISIBLE (-2175 2025);
FORCEPROP 2 LAST CDS_SEC 1
J 0
(-2175 2025);
DISPLAY 1.021277 (-2175 2025);
DISPLAY INVISIBLE (-2175 2025);
FORCEPROP 1 LAST PATH I29
J 0
(-2175 1975);
DISPLAY 0.978723 (-2175 1975);
PAINT WHITE (-2175 1975);
DISPLAY INVISIBLE (-2175 1975);
FORCEADD OFFPAGE..1
(-2250 3375);
FORCEPROP 2 LAST $XR0 206 
J 0
(-2532 3375);
DISPLAY 0.638298 (-2532 3375);
PAINT MONO (-2532 3375);
FORCEPROP 2 LAST CDS_LIB standard
J 0
(-2250 3375);
DISPLAY INVISIBLE (-2250 3375);
FORCEPROP 1 LAST OFFPAGE TRUE
J 0
(-1925 3250);
DISPLAY 0.872340 (-1925 3250);
DISPLAY INVISIBLE (-1925 3250);
FORCEPROP 1 LAST COMMENT_BODY TRUE
J 0
(-2125 3275);
DISPLAY 0.872340 (-2125 3275);
PAINT GREEN (-2125 3275);
DISPLAY INVISIBLE (-2125 3275);
FORCEPROP 2 LAST PATH I3
J 0
(-2525 3425);
DISPLAY 1.021277 (-2525 3425);
DISPLAY INVISIBLE (-2525 3425);
FORCEADD OFFPAGE..4
(3650 3575);
FORCEPROP 2 LAST $XR0 119 
J 0
(3836 3575);
DISPLAY 0.638298 (3836 3575);
PAINT MONO (3836 3575);
FORCEPROP 2 LAST CDS_LIB standard
J 0
(3650 3575);
PAINT MONO (3650 3575);
DISPLAY INVISIBLE (3650 3575);
FORCEPROP 1 LAST OFFPAGE TRUE
J 0
(3975 3450);
DISPLAY 1.170213 (3975 3450);
PAINT GREEN (3975 3450);
DISPLAY INVISIBLE (3975 3450);
FORCEPROP 1 LAST COMMENT_BODY TRUE
J 0
(3625 3475);
DISPLAY 1.170213 (3625 3475);
PAINT GREEN (3625 3475);
DISPLAY INVISIBLE (3625 3475);
FORCEPROP 2 LAST PATH I30
J 0
(3975 3625);
DISPLAY 1.021277 (3975 3625);
DISPLAY INVISIBLE (3975 3625);
FORCEADD OFFPAGE..4
(3650 3525);
FORCEPROP 2 LAST $XR0 119 
J 0
(3836 3525);
DISPLAY 0.638298 (3836 3525);
PAINT MONO (3836 3525);
FORCEPROP 2 LAST CDS_LIB standard
J 0
(3650 3525);
PAINT MONO (3650 3525);
DISPLAY INVISIBLE (3650 3525);
FORCEPROP 1 LAST OFFPAGE TRUE
J 0
(3975 3400);
DISPLAY 1.170213 (3975 3400);
PAINT GREEN (3975 3400);
DISPLAY INVISIBLE (3975 3400);
FORCEPROP 1 LAST COMMENT_BODY TRUE
J 0
(3625 3425);
DISPLAY 1.170213 (3625 3425);
PAINT GREEN (3625 3425);
DISPLAY INVISIBLE (3625 3425);
FORCEPROP 2 LAST PATH I31
J 0
(3975 3575);
DISPLAY 1.021277 (3975 3575);
DISPLAY INVISIBLE (3975 3575);
FORCEADD OFFPAGE..4
(3650 3475);
FORCEPROP 2 LAST $XR0 119 
J 0
(3836 3475);
DISPLAY 0.638298 (3836 3475);
PAINT MONO (3836 3475);
FORCEPROP 2 LAST CDS_LIB standard
J 0
(3650 3475);
PAINT MONO (3650 3475);
DISPLAY INVISIBLE (3650 3475);
FORCEPROP 1 LAST OFFPAGE TRUE
J 0
(3975 3350);
DISPLAY 1.170213 (3975 3350);
PAINT GREEN (3975 3350);
DISPLAY INVISIBLE (3975 3350);
FORCEPROP 1 LAST COMMENT_BODY TRUE
J 0
(3625 3375);
DISPLAY 1.170213 (3625 3375);
PAINT GREEN (3625 3375);
DISPLAY INVISIBLE (3625 3375);
FORCEPROP 2 LAST PATH I32
J 0
(3975 3525);
DISPLAY 1.021277 (3975 3525);
DISPLAY INVISIBLE (3975 3525);
FORCEADD OFFPAGE..4
(3650 3375);
FORCEPROP 2 LAST $XR0 119 
J 0
(3836 3375);
DISPLAY 0.638298 (3836 3375);
PAINT MONO (3836 3375);
FORCEPROP 2 LAST CDS_LIB standard
J 0
(3650 3375);
PAINT MONO (3650 3375);
DISPLAY INVISIBLE (3650 3375);
FORCEPROP 1 LAST OFFPAGE TRUE
J 0
(3975 3250);
DISPLAY 1.170213 (3975 3250);
PAINT GREEN (3975 3250);
DISPLAY INVISIBLE (3975 3250);
FORCEPROP 1 LAST COMMENT_BODY TRUE
J 0
(3625 3275);
DISPLAY 1.170213 (3625 3275);
PAINT GREEN (3625 3275);
DISPLAY INVISIBLE (3625 3275);
FORCEPROP 2 LAST PATH I33
J 0
(3825 3450);
DISPLAY 1.021277 (3825 3450);
DISPLAY INVISIBLE (3825 3450);
FORCEADD OFFPAGE..4
(3650 3275);
FORCEPROP 2 LAST $XR0 119 
J 0
(3836 3275);
DISPLAY 0.638298 (3836 3275);
PAINT MONO (3836 3275);
FORCEPROP 2 LAST CDS_LIB standard
J 0
(3650 3275);
PAINT MONO (3650 3275);
DISPLAY INVISIBLE (3650 3275);
FORCEPROP 1 LAST OFFPAGE TRUE
J 0
(3975 3150);
DISPLAY 1.170213 (3975 3150);
PAINT GREEN (3975 3150);
DISPLAY INVISIBLE (3975 3150);
FORCEPROP 1 LAST COMMENT_BODY TRUE
J 0
(3625 3175);
DISPLAY 1.170213 (3625 3175);
PAINT GREEN (3625 3175);
DISPLAY INVISIBLE (3625 3175);
FORCEPROP 2 LAST PATH I34
J 0
(3825 3350);
DISPLAY 1.021277 (3825 3350);
DISPLAY INVISIBLE (3825 3350);
FORCEADD OFFPAGE..4
(3650 3175);
FORCEPROP 2 LAST $XR0 119 
J 0
(3836 3175);
DISPLAY 0.638298 (3836 3175);
PAINT MONO (3836 3175);
FORCEPROP 2 LAST CDS_LIB standard
J 0
(3650 3175);
PAINT MONO (3650 3175);
DISPLAY INVISIBLE (3650 3175);
FORCEPROP 1 LAST OFFPAGE TRUE
J 0
(3975 3050);
DISPLAY 1.170213 (3975 3050);
PAINT GREEN (3975 3050);
DISPLAY INVISIBLE (3975 3050);
FORCEPROP 1 LAST COMMENT_BODY TRUE
J 0
(3625 3075);
DISPLAY 1.170213 (3625 3075);
PAINT GREEN (3625 3075);
DISPLAY INVISIBLE (3625 3075);
FORCEPROP 2 LAST PATH I35
J 0
(3825 3250);
DISPLAY 1.021277 (3825 3250);
DISPLAY INVISIBLE (3825 3250);
FORCEADD OFFPAGE..4
(3650 3125);
FORCEPROP 2 LAST $XR0 119 
J 0
(3836 3125);
DISPLAY 0.638298 (3836 3125);
PAINT MONO (3836 3125);
FORCEPROP 2 LAST CDS_LIB standard
J 0
(3650 3125);
PAINT MONO (3650 3125);
DISPLAY INVISIBLE (3650 3125);
FORCEPROP 1 LAST OFFPAGE TRUE
J 0
(3975 3000);
DISPLAY 1.170213 (3975 3000);
PAINT GREEN (3975 3000);
DISPLAY INVISIBLE (3975 3000);
FORCEPROP 1 LAST COMMENT_BODY TRUE
J 0
(3625 3025);
DISPLAY 1.170213 (3625 3025);
PAINT GREEN (3625 3025);
DISPLAY INVISIBLE (3625 3025);
FORCEPROP 2 LAST PATH I36
J 0
(3825 3200);
DISPLAY 1.021277 (3825 3200);
DISPLAY INVISIBLE (3825 3200);
FORCEADD OFFPAGE..4
(3650 3075);
FORCEPROP 2 LAST $XR0 119 
J 0
(3836 3075);
DISPLAY 0.638298 (3836 3075);
PAINT MONO (3836 3075);
FORCEPROP 2 LAST CDS_LIB standard
J 0
(3650 3075);
PAINT MONO (3650 3075);
DISPLAY INVISIBLE (3650 3075);
FORCEPROP 1 LAST OFFPAGE TRUE
J 0
(3975 2950);
DISPLAY 1.170213 (3975 2950);
PAINT GREEN (3975 2950);
DISPLAY INVISIBLE (3975 2950);
FORCEPROP 1 LAST COMMENT_BODY TRUE
J 0
(3625 2975);
DISPLAY 1.170213 (3625 2975);
PAINT GREEN (3625 2975);
DISPLAY INVISIBLE (3625 2975);
FORCEPROP 2 LAST PATH I37
J 0
(3825 3150);
DISPLAY 1.021277 (3825 3150);
DISPLAY INVISIBLE (3825 3150);
FORCEADD OFFPAGE..2
(3650 3025);
FORCEPROP 2 LAST $XR1 214 
J 0
(3959 3025);
DISPLAY 0.638298 (3959 3025);
PAINT MONO (3959 3025);
FORCEPROP 2 LAST $XR0 119 
J 0
(3839 3025);
DISPLAY 0.638298 (3839 3025);
PAINT MONO (3839 3025);
FORCEPROP 2 LAST CDS_LIB standard
J 0
(3650 3025);
PAINT MONO (3650 3025);
DISPLAY INVISIBLE (3650 3025);
FORCEPROP 1 LAST OFFPAGE TRUE
J 0
(3975 2900);
DISPLAY 1.170213 (3975 2900);
PAINT GREEN (3975 2900);
DISPLAY INVISIBLE (3975 2900);
FORCEPROP 1 LAST COMMENT_BODY TRUE
J 0
(3605 2930);
DISPLAY 1.170213 (3605 2930);
PAINT GREEN (3605 2930);
DISPLAY INVISIBLE (3605 2930);
FORCEPROP 2 LAST PATH I38
J 0
(4025 3075);
DISPLAY 1.021277 (4025 3075);
DISPLAY INVISIBLE (4025 3075);
FORCEADD OFFPAGE..2
(3650 2975);
FORCEPROP 2 LAST $XR1 214 
J 0
(3959 2975);
DISPLAY 0.638298 (3959 2975);
PAINT MONO (3959 2975);
FORCEPROP 2 LAST $XR0 119 
J 0
(3839 2975);
DISPLAY 0.638298 (3839 2975);
PAINT MONO (3839 2975);
FORCEPROP 2 LAST CDS_LIB standard
J 0
(3650 2975);
PAINT MONO (3650 2975);
DISPLAY INVISIBLE (3650 2975);
FORCEPROP 1 LAST OFFPAGE TRUE
J 0
(3975 2850);
DISPLAY 1.170213 (3975 2850);
PAINT GREEN (3975 2850);
DISPLAY INVISIBLE (3975 2850);
FORCEPROP 1 LAST COMMENT_BODY TRUE
J 0
(3605 2880);
DISPLAY 1.170213 (3605 2880);
PAINT GREEN (3605 2880);
DISPLAY INVISIBLE (3605 2880);
FORCEPROP 2 LAST PATH I39
J 0
(4025 3025);
DISPLAY 1.021277 (4025 3025);
DISPLAY INVISIBLE (4025 3025);
FORCEADD OFFPAGE..1
(-2250 3575);
FORCEPROP 2 LAST $XR0 206 
J 0
(-2532 3575);
DISPLAY 0.638298 (-2532 3575);
PAINT MONO (-2532 3575);
FORCEPROP 2 LAST CDS_LIB standard
J 0
(-2250 3575);
DISPLAY INVISIBLE (-2250 3575);
FORCEPROP 1 LAST OFFPAGE TRUE
J 0
(-1925 3450);
DISPLAY 0.872340 (-1925 3450);
DISPLAY INVISIBLE (-1925 3450);
FORCEPROP 1 LAST COMMENT_BODY TRUE
J 0
(-2125 3475);
DISPLAY 0.872340 (-2125 3475);
PAINT GREEN (-2125 3475);
DISPLAY INVISIBLE (-2125 3475);
FORCEPROP 2 LAST PATH I4
J 0
(-2525 3625);
DISPLAY 1.021277 (-2525 3625);
DISPLAY INVISIBLE (-2525 3625);
FORCEADD OFFPAGE..2
(3650 2925);
FORCEPROP 2 LAST $XR1 214 
J 0
(3959 2925);
DISPLAY 0.638298 (3959 2925);
PAINT MONO (3959 2925);
FORCEPROP 2 LAST $XR0 119 
J 0
(3839 2925);
DISPLAY 0.638298 (3839 2925);
PAINT MONO (3839 2925);
FORCEPROP 2 LAST CDS_LIB standard
J 0
(3650 2925);
PAINT MONO (3650 2925);
DISPLAY INVISIBLE (3650 2925);
FORCEPROP 1 LAST OFFPAGE TRUE
J 0
(3975 2800);
DISPLAY 1.170213 (3975 2800);
PAINT GREEN (3975 2800);
DISPLAY INVISIBLE (3975 2800);
FORCEPROP 1 LAST COMMENT_BODY TRUE
J 0
(3605 2830);
DISPLAY 1.170213 (3605 2830);
PAINT GREEN (3605 2830);
DISPLAY INVISIBLE (3605 2830);
FORCEPROP 2 LAST PATH I40
J 0
(4025 2975);
DISPLAY 1.021277 (4025 2975);
DISPLAY INVISIBLE (4025 2975);
FORCEADD OFFPAGE..2
(3650 2825);
FORCEPROP 2 LAST $XR1 214 
J 0
(3959 2825);
DISPLAY 0.638298 (3959 2825);
PAINT MONO (3959 2825);
FORCEPROP 2 LAST $XR0 119 
J 0
(3839 2825);
DISPLAY 0.638298 (3839 2825);
PAINT MONO (3839 2825);
FORCEPROP 2 LAST CDS_LIB standard
J 0
(3650 2825);
PAINT MONO (3650 2825);
DISPLAY INVISIBLE (3650 2825);
FORCEPROP 1 LAST OFFPAGE TRUE
J 0
(3975 2700);
DISPLAY 1.170213 (3975 2700);
PAINT GREEN (3975 2700);
DISPLAY INVISIBLE (3975 2700);
FORCEPROP 1 LAST COMMENT_BODY TRUE
J 0
(3605 2730);
DISPLAY 1.170213 (3605 2730);
PAINT GREEN (3605 2730);
DISPLAY INVISIBLE (3605 2730);
FORCEPROP 2 LAST PATH I41
J 0
(3825 2900);
DISPLAY 1.021277 (3825 2900);
DISPLAY INVISIBLE (3825 2900);
FORCEADD OFFPAGE..2
(3650 2875);
FORCEPROP 2 LAST $XR1 214 
J 0
(3959 2875);
DISPLAY 0.638298 (3959 2875);
PAINT MONO (3959 2875);
FORCEPROP 2 LAST $XR0 119 
J 0
(3839 2875);
DISPLAY 0.638298 (3839 2875);
PAINT MONO (3839 2875);
FORCEPROP 2 LAST CDS_LIB standard
J 0
(3650 2875);
PAINT MONO (3650 2875);
DISPLAY INVISIBLE (3650 2875);
FORCEPROP 1 LAST OFFPAGE TRUE
J 0
(3975 2750);
DISPLAY 1.170213 (3975 2750);
PAINT GREEN (3975 2750);
DISPLAY INVISIBLE (3975 2750);
FORCEPROP 1 LAST COMMENT_BODY TRUE
J 0
(3605 2780);
DISPLAY 1.170213 (3605 2780);
PAINT GREEN (3605 2780);
DISPLAY INVISIBLE (3605 2780);
FORCEPROP 2 LAST PATH I42
J 0
(3825 2950);
DISPLAY 1.021277 (3825 2950);
DISPLAY INVISIBLE (3825 2950);
FORCEADD OFFPAGE..4
(3650 2675);
FORCEPROP 2 LAST $XR0 119 
J 0
(3836 2675);
DISPLAY 0.638298 (3836 2675);
PAINT MONO (3836 2675);
FORCEPROP 2 LAST CDS_LIB standard
J 0
(3650 2675);
PAINT MONO (3650 2675);
DISPLAY INVISIBLE (3650 2675);
FORCEPROP 1 LAST OFFPAGE TRUE
J 0
(3975 2550);
DISPLAY 1.170213 (3975 2550);
PAINT GREEN (3975 2550);
DISPLAY INVISIBLE (3975 2550);
FORCEPROP 1 LAST COMMENT_BODY TRUE
J 0
(3625 2575);
DISPLAY 1.170213 (3625 2575);
PAINT GREEN (3625 2575);
DISPLAY INVISIBLE (3625 2575);
FORCEPROP 2 LAST PATH I43
J 0
(3825 2750);
DISPLAY 1.021277 (3825 2750);
DISPLAY INVISIBLE (3825 2750);
FORCEADD OFFPAGE..4
(3650 2575);
FORCEPROP 2 LAST $XR0 119 
J 0
(3836 2575);
DISPLAY 0.638298 (3836 2575);
PAINT MONO (3836 2575);
FORCEPROP 2 LAST CDS_LIB standard
J 0
(3650 2575);
PAINT MONO (3650 2575);
DISPLAY INVISIBLE (3650 2575);
FORCEPROP 1 LAST OFFPAGE TRUE
J 0
(3975 2450);
DISPLAY 1.170213 (3975 2450);
PAINT GREEN (3975 2450);
DISPLAY INVISIBLE (3975 2450);
FORCEPROP 1 LAST COMMENT_BODY TRUE
J 0
(3625 2475);
DISPLAY 1.170213 (3625 2475);
PAINT GREEN (3625 2475);
DISPLAY INVISIBLE (3625 2475);
FORCEPROP 2 LAST PATH I44
J 0
(3825 2650);
DISPLAY 1.021277 (3825 2650);
DISPLAY INVISIBLE (3825 2650);
FORCEADD OFFPAGE..4
(3650 2525);
FORCEPROP 2 LAST $XR0 119 
J 0
(3836 2525);
DISPLAY 0.638298 (3836 2525);
PAINT MONO (3836 2525);
FORCEPROP 2 LAST CDS_LIB standard
J 0
(3650 2525);
PAINT MONO (3650 2525);
DISPLAY INVISIBLE (3650 2525);
FORCEPROP 1 LAST OFFPAGE TRUE
J 0
(3975 2400);
DISPLAY 1.170213 (3975 2400);
PAINT GREEN (3975 2400);
DISPLAY INVISIBLE (3975 2400);
FORCEPROP 1 LAST COMMENT_BODY TRUE
J 0
(3625 2425);
DISPLAY 1.170213 (3625 2425);
PAINT GREEN (3625 2425);
DISPLAY INVISIBLE (3625 2425);
FORCEPROP 2 LAST PATH I45
J 0
(3825 2600);
DISPLAY 1.021277 (3825 2600);
DISPLAY INVISIBLE (3825 2600);
FORCEADD OFFPAGE..1
(-2250 3525);
FORCEPROP 2 LAST $XR0 206 
J 0
(-2532 3525);
DISPLAY 0.638298 (-2532 3525);
PAINT MONO (-2532 3525);
FORCEPROP 2 LAST CDS_LIB standard
J 0
(-2250 3525);
DISPLAY INVISIBLE (-2250 3525);
FORCEPROP 1 LAST OFFPAGE TRUE
J 0
(-1925 3400);
DISPLAY 0.872340 (-1925 3400);
DISPLAY INVISIBLE (-1925 3400);
FORCEPROP 1 LAST COMMENT_BODY TRUE
J 0
(-2125 3425);
DISPLAY 0.872340 (-2125 3425);
PAINT GREEN (-2125 3425);
DISPLAY INVISIBLE (-2125 3425);
FORCEPROP 2 LAST PATH I5
J 0
(-2525 3575);
DISPLAY 1.021277 (-2525 3575);
DISPLAY INVISIBLE (-2525 3575);
FORCEADD OFFPAGE..2
(3650 1725);
FORCEPROP 2 LAST $XR0 133 
J 0
(3839 1725);
DISPLAY 0.638298 (3839 1725);
PAINT MONO (3839 1725);
FORCEPROP 2 LAST CDS_LIB standard
J 0
(3650 1725);
PAINT MONO (3650 1725);
DISPLAY INVISIBLE (3650 1725);
FORCEPROP 1 LAST OFFPAGE TRUE
J 0
(3975 1600);
DISPLAY 1.170213 (3975 1600);
PAINT GREEN (3975 1600);
DISPLAY INVISIBLE (3975 1600);
FORCEPROP 1 LAST COMMENT_BODY TRUE
J 0
(3605 1630);
DISPLAY 1.170213 (3605 1630);
PAINT GREEN (3605 1630);
DISPLAY INVISIBLE (3605 1630);
FORCEPROP 2 LAST PATH I51
J 0
(3825 1800);
DISPLAY 1.021277 (3825 1800);
DISPLAY INVISIBLE (3825 1800);
FORCEADD OFFPAGE..2
(3650 2425);
FORCEPROP 2 LAST $XR0 128 
J 0
(3839 2425);
DISPLAY 0.638298 (3839 2425);
PAINT MONO (3839 2425);
FORCEPROP 2 LAST CDS_LIB standard
J 0
(3650 2425);
PAINT MONO (3650 2425);
DISPLAY INVISIBLE (3650 2425);
FORCEPROP 1 LAST OFFPAGE TRUE
J 0
(3975 2300);
DISPLAY 1.170213 (3975 2300);
PAINT GREEN (3975 2300);
DISPLAY INVISIBLE (3975 2300);
FORCEPROP 1 LAST COMMENT_BODY TRUE
J 0
(3605 2330);
DISPLAY 1.170213 (3605 2330);
PAINT GREEN (3605 2330);
DISPLAY INVISIBLE (3605 2330);
FORCEPROP 2 LAST PATH I53
J 0
(3825 2500);
DISPLAY 1.021277 (3825 2500);
DISPLAY INVISIBLE (3825 2500);
FORCEADD OFFPAGE..2
(3650 2375);
FORCEPROP 2 LAST $XR0 128 
J 0
(3839 2375);
DISPLAY 0.638298 (3839 2375);
PAINT MONO (3839 2375);
FORCEPROP 2 LAST CDS_LIB standard
J 0
(3650 2375);
PAINT MONO (3650 2375);
DISPLAY INVISIBLE (3650 2375);
FORCEPROP 1 LAST OFFPAGE TRUE
J 0
(3975 2250);
DISPLAY 1.170213 (3975 2250);
PAINT GREEN (3975 2250);
DISPLAY INVISIBLE (3975 2250);
FORCEPROP 1 LAST COMMENT_BODY TRUE
J 0
(3605 2280);
DISPLAY 1.170213 (3605 2280);
PAINT GREEN (3605 2280);
DISPLAY INVISIBLE (3605 2280);
FORCEPROP 2 LAST PATH I54
J 0
(3825 2450);
DISPLAY 1.021277 (3825 2450);
DISPLAY INVISIBLE (3825 2450);
FORCEADD OFFPAGE..2
(3650 2325);
FORCEPROP 2 LAST $XR0 128 
J 0
(3839 2325);
DISPLAY 0.638298 (3839 2325);
PAINT MONO (3839 2325);
FORCEPROP 2 LAST CDS_LIB standard
J 0
(3650 2325);
PAINT MONO (3650 2325);
DISPLAY INVISIBLE (3650 2325);
FORCEPROP 1 LAST OFFPAGE TRUE
J 0
(3975 2200);
DISPLAY 1.170213 (3975 2200);
PAINT GREEN (3975 2200);
DISPLAY INVISIBLE (3975 2200);
FORCEPROP 1 LAST COMMENT_BODY TRUE
J 0
(3605 2230);
DISPLAY 1.170213 (3605 2230);
PAINT GREEN (3605 2230);
DISPLAY INVISIBLE (3605 2230);
FORCEPROP 2 LAST PATH I55
J 0
(3825 2400);
DISPLAY 1.021277 (3825 2400);
DISPLAY INVISIBLE (3825 2400);
FORCEADD OFFPAGE..2
(3650 2275);
FORCEPROP 2 LAST $XR0 128 
J 0
(3839 2275);
DISPLAY 0.638298 (3839 2275);
PAINT MONO (3839 2275);
FORCEPROP 2 LAST CDS_LIB standard
J 0
(3650 2275);
PAINT MONO (3650 2275);
DISPLAY INVISIBLE (3650 2275);
FORCEPROP 1 LAST OFFPAGE TRUE
J 0
(3975 2150);
DISPLAY 1.170213 (3975 2150);
PAINT GREEN (3975 2150);
DISPLAY INVISIBLE (3975 2150);
FORCEPROP 1 LAST COMMENT_BODY TRUE
J 0
(3605 2180);
DISPLAY 1.170213 (3605 2180);
PAINT GREEN (3605 2180);
DISPLAY INVISIBLE (3605 2180);
FORCEPROP 2 LAST PATH I56
J 0
(3825 2350);
DISPLAY 1.021277 (3825 2350);
DISPLAY INVISIBLE (3825 2350);
FORCEADD SOCKET4677_AZIF0045P001C01CS..1
(700 2650);
FORCEPROP 1 LAST PART_NUMBER DGA^7000023
J 0
(-400 3850);
DISPLAY 0.723404 (-400 3850);
PAINT GREEN (-400 3850);
DISPLAY INVISIBLE (-400 3850);
FORCEPROP 2 LAST PART_TYPE SMLF
J 0
(-400 4025);
DISPLAY 1.021277 (-400 4025);
FORCEPROP 1 LAST MATERIAL IO
J 0
(-400 3775);
DISPLAY 0.723404 (-400 3775);
PAINT GREEN (-400 3775);
FORCEPROP 2 LAST VALUE SOCKET4677_AZIF0045-P001C01CS
J 0
(-400 3975);
DISPLAY 1.021277 (-400 3975);
FORCEPROP 1 LAST $LOCATION U2
J 0
(-400 3925);
DISPLAY 0.723404 (-400 3925);
PAINT GREEN (-400 3925);
FORCEPROP 0 LASTPIN (-525 3525) $PN AT30
J 2
(-535 3535);
DISPLAY 0.680851 (-535 3535);
PAINT MONO (-535 3535);
FORCEPROP 0 LASTPIN (-525 3575) $PN AV30
J 2
(-535 3585);
DISPLAY 0.680851 (-535 3585);
PAINT MONO (-535 3585);
FORCEPROP 0 LASTPIN (-525 3375) $PN CY28
J 2
(-535 3385);
DISPLAY 0.680851 (-535 3385);
PAINT MONO (-535 3385);
FORCEPROP 0 LASTPIN (-525 3425) $PN CW29
J 2
(-535 3435);
DISPLAY 0.680851 (-535 3435);
PAINT MONO (-535 3435);
FORCEPROP 0 LASTPIN (-525 3225) $PN AU29
J 2
(-535 3235);
DISPLAY 0.680851 (-535 3235);
PAINT MONO (-535 3235);
FORCEPROP 0 LASTPIN (-525 3275) $PN AV28
J 2
(-535 3285);
DISPLAY 0.680851 (-535 3285);
PAINT MONO (-535 3285);
FORCEPROP 0 LASTPIN (-525 3075) $PN CW27
J 2
(-535 3085);
DISPLAY 0.680851 (-535 3085);
PAINT MONO (-535 3085);
FORCEPROP 0 LASTPIN (-525 3125) $PN DA27
J 2
(-535 3135);
DISPLAY 0.680851 (-535 3135);
PAINT MONO (-535 3135);
FORCEPROP 0 LASTPIN (1925 3575) $PN AT18
J 0
(1935 3585);
DISPLAY 0.680851 (1935 3585);
PAINT MONO (1935 3585);
FORCEPROP 0 LASTPIN (1925 3525) $PN BN23
J 0
(1935 3535);
DISPLAY 0.680851 (1935 3535);
PAINT MONO (1935 3535);
FORCEPROP 0 LASTPIN (1925 2425) $PN AU50
J 0
(1935 2435);
DISPLAY 0.680851 (1935 2435);
PAINT MONO (1935 2435);
FORCEPROP 0 LASTPIN (1925 2375) $PN AV51
J 0
(1935 2385);
DISPLAY 0.680851 (1935 2385);
PAINT MONO (1935 2385);
FORCEPROP 0 LASTPIN (1925 2325) $PN CY42
J 0
(1935 2335);
DISPLAY 0.680851 (1935 2335);
PAINT MONO (1935 2335);
FORCEPROP 0 LASTPIN (1925 2275) $PN CY55
J 0
(1935 2285);
DISPLAY 0.680851 (1935 2285);
PAINT MONO (1935 2285);
FORCEPROP 0 LASTPIN (1925 3375) $PN AW17
J 0
(1935 3385);
DISPLAY 0.680851 (1935 3385);
PAINT MONO (1935 3385);
FORCEPROP 0 LASTPIN (1925 3275) $PN AU17
J 0
(1935 3285);
DISPLAY 0.680851 (1935 3285);
PAINT MONO (1935 3285);
FORCEPROP 0 LASTPIN (1925 3475) $PN CY59
J 0
(1935 3485);
DISPLAY 0.680851 (1935 3485);
PAINT MONO (1935 3485);
FORCEPROP 0 LASTPIN (-525 1925) $PN BH24
J 2
(-535 1935);
DISPLAY 0.680851 (-535 1935);
PAINT MONO (-535 1935);
FORCEPROP 0 LASTPIN (1925 3025) $PN BL64
J 0
(1935 3035);
DISPLAY 0.680851 (1935 3035);
PAINT MONO (1935 3035);
FORCEPROP 0 LASTPIN (1925 2975) $PN AY63
J 0
(1935 2985);
DISPLAY 0.680851 (1935 2985);
PAINT MONO (1935 2985);
FORCEPROP 0 LASTPIN (1925 2925) $PN BN64
J 0
(1935 2935);
DISPLAY 0.680851 (1935 2935);
PAINT MONO (1935 2935);
FORCEPROP 0 LASTPIN (-525 2075) $PN BP26
J 2
(-535 2085);
DISPLAY 0.680851 (-535 2085);
PAINT MONO (-535 2085);
FORCEPROP 0 LASTPIN (-525 2025) $PN AV22
J 2
(-535 2035);
DISPLAY 0.680851 (-535 2035);
PAINT MONO (-535 2035);
FORCEPROP 0 LASTPIN (1925 2875) $PN BG72
J 0
(1935 2885);
DISPLAY 0.680851 (1935 2885);
PAINT MONO (1935 2885);
FORCEPROP 0 LASTPIN (1925 2825) $PN BH71
J 0
(1935 2835);
DISPLAY 0.680851 (1935 2835);
PAINT MONO (1935 2835);
FORCEPROP 0 LASTPIN (1925 2725) $PN DA52
J 0
(1935 2735);
DISPLAY 0.680851 (1935 2735);
PAINT MONO (1935 2735);
FORCEPROP 0 LASTPIN (1925 2675) $PN AU23
J 0
(1935 2685);
DISPLAY 0.680851 (1935 2685);
PAINT MONO (1935 2685);
FORCEPROP 0 LASTPIN (1925 3175) $PN CW60
J 0
(1935 3185);
DISPLAY 0.680851 (1935 3185);
PAINT MONO (1935 3185);
FORCEPROP 0 LASTPIN (1925 3125) $PN CY61
J 0
(1935 3135);
DISPLAY 0.680851 (1935 3135);
PAINT MONO (1935 3135);
FORCEPROP 0 LASTPIN (1925 3075) $PN CT61
J 0
(1935 3085);
DISPLAY 0.680851 (1935 3085);
PAINT MONO (1935 3085);
FORCEPROP 0 LASTPIN (-525 1775) $PN BT24
J 2
(-535 1785);
DISPLAY 0.680851 (-535 1785);
PAINT MONO (-535 1785);
FORCEPROP 0 LASTPIN (-525 1825) $PN BV24
J 2
(-535 1835);
DISPLAY 0.680851 (-535 1835);
PAINT MONO (-535 1835);
FORCEPROP 0 LASTPIN (1925 1725) $PN BW25
J 0
(1935 1735);
DISPLAY 0.680851 (1935 1735);
PAINT MONO (1935 1735);
FORCEPROP 0 LASTPIN (-525 1725) $PN BR25
J 2
(-535 1735);
DISPLAY 0.680851 (-535 1735);
PAINT MONO (-535 1735);
FORCEPROP 0 LASTPIN (1925 2575) $PN BT26
J 0
(1935 2585);
DISPLAY 0.680851 (1935 2585);
PAINT MONO (1935 2585);
FORCEPROP 0 LASTPIN (1925 2525) $PN CT20
J 0
(1935 2535);
DISPLAY 0.680851 (1935 2535);
PAINT MONO (1935 2535);
FORCEPROP 0 LASTPIN (-525 2925) $PN CW31
J 2
(-535 2935);
DISPLAY 0.680851 (-535 2935);
PAINT MONO (-535 2935);
FORCEPROP 0 LASTPIN (-525 2975) $PN CY32
J 2
(-535 2985);
DISPLAY 0.680851 (-535 2985);
PAINT MONO (-535 2985);
FORCEPROP 0 LASTPIN (-525 2375) $PN BT22
J 2
(-535 2385);
DISPLAY 0.680851 (-535 2385);
PAINT MONO (-535 2385);
FORCEPROP 0 LASTPIN (-525 2325) $PN BY22
J 2
(-535 2335);
DISPLAY 0.680851 (-535 2335);
PAINT MONO (-535 2335);
FORCEPROP 0 LASTPIN (-525 2225) $PN CU17
J 2
(-535 2235);
DISPLAY 0.680851 (-535 2235);
PAINT MONO (-535 2235);
FORCEPROP 0 LASTPIN (-525 2175) $PN CT18
J 2
(-535 2185);
DISPLAY 0.680851 (-535 2185);
PAINT MONO (-535 2185);
FORCEPROP 0 LASTPIN (1925 2075) $PN BR23
J 0
(1935 2085);
DISPLAY 0.680851 (1935 2085);
PAINT MONO (1935 2085);
FORCEPROP 0 LASTPIN (1925 2175) $PN BY24
J 0
(1935 2185);
DISPLAY 0.680851 (1935 2185);
PAINT MONO (1935 2185);
FORCEPROP 0 LASTPIN (-525 2475) $PN CD71
J 2
(-535 2485);
DISPLAY 0.680851 (-535 2485);
PAINT MONO (-535 2485);
FORCEPROP 0 LASTPIN (-525 2525) $PN CE70
J 2
(-535 2535);
DISPLAY 0.680851 (-535 2535);
PAINT MONO (-535 2535);
FORCEPROP 0 LASTPIN (-525 2625) $PN CJ72
J 2
(-535 2635);
DISPLAY 0.680851 (-535 2635);
PAINT MONO (-535 2635);
FORCEPROP 0 LASTPIN (-525 2675) $PN CL72
J 2
(-535 2685);
DISPLAY 0.680851 (-535 2685);
PAINT MONO (-535 2685);
FORCEPROP 0 LASTPIN (-525 2775) $PN D4
J 2
(-535 2785);
DISPLAY 0.680851 (-535 2785);
PAINT MONO (-535 2785);
FORCEPROP 0 LASTPIN (-525 2825) $PN G5
J 2
(-535 2835);
DISPLAY 0.680851 (-535 2835);
PAINT MONO (-535 2835);
FORCEPROP 2 LAST CDS_LIB pure_quanta
J 0
(700 2650);
DISPLAY INVISIBLE (700 2650);
FORCEPROP 1 LAST NEEDS_NO_SIZE TRUE
J 0
(700 2650);
DISPLAY 0.723404 (700 2650);
PAINT GREEN (700 2650);
DISPLAY INVISIBLE (700 2650);
FORCEPROP 1 LAST CDS_LMAN_SYM_OUTLINE -1100,1100,1050,-1050
J 0
(700 2650);
DISPLAY 0.468085 (700 2650);
PAINT GREEN (700 2650);
DISPLAY INVISIBLE (700 2650);
FORCEPROP 2 LAST CDS_LOCATION U2
J 0
(-400 4075);
DISPLAY 1.021277 (-400 4075);
DISPLAY INVISIBLE (-400 4075);
FORCEPROP 0 LAST $SEC 1
J 0
(-400 4075);
DISPLAY 0.680851 (-400 4075);
PAINT MONO (-400 4075);
DISPLAY INVISIBLE (-400 4075);
FORCEPROP 2 LAST CDS_SEC 1
J 0
(-400 4075);
DISPLAY 1.021277 (-400 4075);
DISPLAY INVISIBLE (-400 4075);
FORCEPROP 1 LAST PATH I57
J 0
(700 2650);
DISPLAY 0.723404 (700 2650);
PAINT GREEN (700 2650);
DISPLAY INVISIBLE (700 2650);
FORCEADD OFFPAGE..1
(-2250 2675);
FORCEPROP 2 LAST $XR0 119 
J 0
(-2532 2675);
DISPLAY 0.638298 (-2532 2675);
PAINT MONO (-2532 2675);
FORCEPROP 2 LAST CDS_LIB standard
J 0
(-2250 2675);
PAINT MONO (-2250 2675);
DISPLAY INVISIBLE (-2250 2675);
FORCEPROP 1 LAST OFFPAGE TRUE
J 0
(-1925 2550);
DISPLAY 0.872340 (-1925 2550);
DISPLAY INVISIBLE (-1925 2550);
FORCEPROP 1 LAST COMMENT_BODY TRUE
J 0
(-2125 2575);
DISPLAY 0.872340 (-2125 2575);
PAINT GREEN (-2125 2575);
DISPLAY INVISIBLE (-2125 2575);
FORCEPROP 2 LAST PATH I58
J 0
(-2525 2725);
DISPLAY 1.021277 (-2525 2725);
DISPLAY INVISIBLE (-2525 2725);
FORCEADD OFFPAGE..1
(-2250 2625);
FORCEPROP 2 LAST $XR0 119 
J 0
(-2532 2625);
DISPLAY 0.638298 (-2532 2625);
PAINT MONO (-2532 2625);
FORCEPROP 2 LAST CDS_LIB standard
J 0
(-2250 2625);
PAINT MONO (-2250 2625);
DISPLAY INVISIBLE (-2250 2625);
FORCEPROP 1 LAST OFFPAGE TRUE
J 0
(-1925 2500);
DISPLAY 0.872340 (-1925 2500);
DISPLAY INVISIBLE (-1925 2500);
FORCEPROP 1 LAST COMMENT_BODY TRUE
J 0
(-2125 2525);
DISPLAY 0.872340 (-2125 2525);
PAINT GREEN (-2125 2525);
DISPLAY INVISIBLE (-2125 2525);
FORCEPROP 2 LAST PATH I59
J 0
(-2525 2675);
DISPLAY 1.021277 (-2525 2675);
DISPLAY INVISIBLE (-2525 2675);
FORCEADD OFFPAGE..1
(-2250 3425);
FORCEPROP 2 LAST $XR0 206 
J 0
(-2532 3425);
DISPLAY 0.638298 (-2532 3425);
PAINT MONO (-2532 3425);
FORCEPROP 2 LAST CDS_LIB standard
J 0
(-2250 3425);
DISPLAY INVISIBLE (-2250 3425);
FORCEPROP 1 LAST OFFPAGE TRUE
J 0
(-1925 3300);
DISPLAY 0.872340 (-1925 3300);
DISPLAY INVISIBLE (-1925 3300);
FORCEPROP 1 LAST COMMENT_BODY TRUE
J 0
(-2125 3325);
DISPLAY 0.872340 (-2125 3325);
PAINT GREEN (-2125 3325);
DISPLAY INVISIBLE (-2125 3325);
FORCEPROP 2 LAST PATH I6
J 0
(-2525 3475);
DISPLAY 1.021277 (-2525 3475);
DISPLAY INVISIBLE (-2525 3475);
FORCEADD OFFPAGE..4
(3650 2175);
FORCEPROP 2 LAST $XR0 119 
J 0
(3836 2175);
DISPLAY 0.638298 (3836 2175);
PAINT MONO (3836 2175);
FORCEPROP 2 LAST CDS_LIB standard
J 0
(3650 2175);
PAINT MONO (3650 2175);
DISPLAY INVISIBLE (3650 2175);
FORCEPROP 1 LAST OFFPAGE TRUE
J 0
(3975 2050);
DISPLAY 1.170213 (3975 2050);
PAINT GREEN (3975 2050);
DISPLAY INVISIBLE (3975 2050);
FORCEPROP 1 LAST COMMENT_BODY TRUE
J 0
(3625 2075);
DISPLAY 1.170213 (3625 2075);
PAINT GREEN (3625 2075);
DISPLAY INVISIBLE (3625 2075);
FORCEPROP 2 LAST PATH I60
J 0
(3850 2225);
DISPLAY 1.021277 (3850 2225);
DISPLAY INVISIBLE (3850 2225);
FORCEADD OFFPAGE..1
(-2250 3225);
FORCEPROP 2 LAST $XR0 206 
J 0
(-2532 3225);
DISPLAY 0.638298 (-2532 3225);
PAINT MONO (-2532 3225);
FORCEPROP 2 LAST CDS_LIB standard
J 0
(-2250 3225);
DISPLAY INVISIBLE (-2250 3225);
FORCEPROP 1 LAST OFFPAGE TRUE
J 0
(-1925 3100);
DISPLAY 0.872340 (-1925 3100);
DISPLAY INVISIBLE (-1925 3100);
FORCEPROP 1 LAST COMMENT_BODY TRUE
J 0
(-2125 3125);
DISPLAY 0.872340 (-2125 3125);
PAINT GREEN (-2125 3125);
DISPLAY INVISIBLE (-2125 3125);
FORCEPROP 2 LAST PATH I7
J 0
(-2525 3275);
DISPLAY 1.021277 (-2525 3275);
DISPLAY INVISIBLE (-2525 3275);
FORCEADD OFFPAGE..1
(-2250 3075);
FORCEPROP 2 LAST $XR0 206 
J 0
(-2532 3075);
DISPLAY 0.638298 (-2532 3075);
PAINT MONO (-2532 3075);
FORCEPROP 2 LAST CDS_LIB standard
J 0
(-2250 3075);
DISPLAY INVISIBLE (-2250 3075);
FORCEPROP 1 LAST OFFPAGE TRUE
J 0
(-1925 2950);
DISPLAY 0.872340 (-1925 2950);
DISPLAY INVISIBLE (-1925 2950);
FORCEPROP 1 LAST COMMENT_BODY TRUE
J 0
(-2125 2975);
DISPLAY 0.872340 (-2125 2975);
PAINT GREEN (-2125 2975);
DISPLAY INVISIBLE (-2125 2975);
FORCEPROP 2 LAST PATH I8
J 0
(-2525 3125);
DISPLAY 1.021277 (-2525 3125);
DISPLAY INVISIBLE (-2525 3125);
FORCEADD OFFPAGE..1
(-2250 3125);
FORCEPROP 2 LAST $XR0 206 
J 0
(-2532 3125);
DISPLAY 0.638298 (-2532 3125);
PAINT MONO (-2532 3125);
FORCEPROP 2 LAST CDS_LIB standard
J 0
(-2250 3125);
DISPLAY INVISIBLE (-2250 3125);
FORCEPROP 1 LAST OFFPAGE TRUE
J 0
(-1925 3000);
DISPLAY 0.872340 (-1925 3000);
DISPLAY INVISIBLE (-1925 3000);
FORCEPROP 1 LAST COMMENT_BODY TRUE
J 0
(-2125 3025);
DISPLAY 0.872340 (-2125 3025);
PAINT GREEN (-2125 3025);
DISPLAY INVISIBLE (-2125 3025);
FORCEPROP 2 LAST PATH I9
J 0
(-2525 3175);
DISPLAY 1.021277 (-2525 3175);
DISPLAY INVISIBLE (-2525 3175);
FORCEADD QUANTA_TITLE_BLOCK_C..1
(5000 -1675);
FORCEPROP 0 LAST CDS_CON_LAST_MODIFIED Fri Aug 25 13:59:59 2023
J 0
(3115 -1660);
PAINT MONO (3115 -1660);
DISPLAY INVISIBLE (3115 -1660);
FORCEPROP 2 LAST CUSTOM_TXT_CDS <XR_PAGE_TITLE>
J 0
(-2890 3575);
DISPLAY 0.638298 (-2890 3575);
PAINT PINK (-2890 3575);
DISPLAY INVISIBLE (-2890 3575);
FORCEPROP 2 LAST CUSTOM_TXT_CDS <CON_PAGE_NUM> OF <CON_TOTAL_PAGES>
J 0
(4554 -1657);
DISPLAY 0.978723 (4554 -1657);
FORCEPROP 2 LAST CUSTOM_TXT_CDS <Q_REV>
J 0
(4816 -1572);
DISPLAY 1.212766 (4816 -1572);
FORCEPROP 2 LAST CUSTOM_TXT_CDS <Q_PROJ>
J 0
(2618 -1573);
DISPLAY 1.212766 (2618 -1573);
FORCEPROP 2 LAST CUSTOM_TXT_CDS <Q_NUMBER>
J 0
(3597 -1572);
DISPLAY 1.212766 (3597 -1572);
FORCEPROP 2 LAST CUSTOM_TXT_CDS <NAME_2>
J 0
(1825 -1625);
FORCEPROP 2 LAST CUSTOM_TXT_CDS <NAME_1>
J 0
(1825 -1500);
FORCEPROP 2 LAST CUSTOM_TXT_CDS <CON_LAST_MODIFIED>
J 0
(3115 -1660);
DISPLAY 0.978723 (3115 -1660);
FORCEPROP 1 LAST Q_TITLE SPR CPU0 MISC:CLK/JTAG/STRAPS(1/30)
J 0
(-4366 -1649);
DISPLAY 1.957447 (-4366 -1649);
PAINT GREEN (-4366 -1649);
FORCEPROP 1 LAST Q_DEPT 
J 1
(1237 -1626);
DISPLAY 1.957447 (1237 -1626);
PAINT GREEN (1237 -1626);
FORCEPROP 2 LAST CDS_LIB pure_quanta
J 0
(5000 -1675);
PAINT MONO (5000 -1675);
DISPLAY INVISIBLE (5000 -1675);
FORCEPROP 1 LAST CDS_LMAN_SYM_OUTLINE -9475,6775,100,-125
J 0
(5000 -1675);
DISPLAY 0.468085 (5000 -1675);
PAINT GREEN (5000 -1675);
DISPLAY INVISIBLE (5000 -1675);
FORCEPROP 2 LAST PAGE_BORDER TRUE
J 0
(-2890 3575);
DISPLAY 0.638298 (-2890 3575);
PAINT PINK (-2890 3575);
DISPLAY INVISIBLE (-2890 3575);
FORCEPROP 2 LAST CDS_XR_PAGE_TITLE CR-13 : @S9S_MB_2U_LIB.S9S_MB_2U(SCH_1):PAGE13
J 0
(-2890 3575);
DISPLAY 0.638298 (-2890 3575);
PAINT PINK (-2890 3575);
DISPLAY INVISIBLE (-2890 3575);
FORCEPROP 1 LAST COMMENT_BODY TRUE
J 0
(5012 -1688);
DISPLAY 0.978723 (5012 -1688);
PAINT GREEN (5012 -1688);
DISPLAY INVISIBLE (5012 -1688);
WIRE 16 -1 (-525 2375)(-2200 2375);
FORCEPROP 2 LAST SIG_NAME I3C_SPD_DDRABCD_CPU0_SCL
J 0
(-2137 2384);
DISPLAY 0.680851 (-2137 2384);
PAINT WHITE (-2137 2384);
WIRE 16 -1 (3600 3125)(1925 3125);
FORCEPROP 2 LAST SIG_NAME PU_CPU0_SOCKET_ID1
J 0
(2184 3134);
DISPLAY 0.680851 (2184 3134);
PAINT WHITE (2184 3134);
WIRE 16 -1 (3600 3175)(1925 3175);
FORCEPROP 2 LAST SIG_NAME PU_CPU0_SOCKET_ID0
J 0
(2184 3184);
DISPLAY 0.680851 (2184 3184);
PAINT WHITE (2184 3184);
WIRE 16 -1 (3600 3275)(1925 3275);
FORCEPROP 2 LAST SIG_NAME PU_CPU0_FRMAGENT
J 0
(2184 3284);
DISPLAY 0.680851 (2184 3284);
PAINT WHITE (2184 3284);
WIRE 16 -1 (3600 3375)(1925 3375);
FORCEPROP 2 LAST SIG_NAME PD_CPU0_DMIMODE_OVERRIDE
J 0
(2184 3384);
DISPLAY 0.680851 (2184 3384);
PAINT WHITE (2184 3384);
WIRE 16 -1 (-525 2975)(-2200 2975);
FORCEPROP 2 LAST SIG_NAME CLK_25M_NSSC_CPU0_DP
J 0
(-2137 2984);
DISPLAY 0.680851 (-2137 2984);
PAINT WHITE (-2137 2984);
WIRE 16 -1 (3600 2525)(1925 2525);
FORCEPROP 2 LAST SIG_NAME PD_CPU0_TXT_PLTEN
J 0
(2184 2534);
DISPLAY 0.680851 (2184 2534);
PAINT WHITE (2184 2534);
WIRE 16 -1 (3600 2575)(1925 2575);
FORCEPROP 2 LAST SIG_NAME PU_CPU0_TXT_AGENT
J 0
(2184 2584);
DISPLAY 0.680851 (2184 2584);
PAINT WHITE (2184 2584);
WIRE 16 -1 (-525 1725)(-2025 1725);
FORCEPROP 2 LAST SIG_NAME JTAG_DBP_CPU0_QS_GTL_R_TMS
J 0
(-1412 1734);
DISPLAY 0.553191 (-1412 1734);
PAINT WHITE (-1412 1734);
WIRE 16 -1 (3600 1725)(1925 1725);
FORCEPROP 2 LAST SIG_NAME JTAG_CPU0_MUX_GTL_TDO
J 0
(2184 1734);
DISPLAY 0.680851 (2184 1734);
PAINT WHITE (2184 1734);
WIRE 16 -1 (-525 1825)(-2025 1825);
FORCEPROP 2 LAST SIG_NAME JTAG_DBP_CPU0_GTL_R_TDI
J 0
(-1412 1834);
DISPLAY 0.553191 (-1412 1834);
PAINT WHITE (-1412 1834);
WIRE 16 -1 (-525 1775)(-2025 1775);
FORCEPROP 2 LAST SIG_NAME JTAG_DBP_CPU0_GTL_R_TCK
J 0
(-1412 1784);
DISPLAY 0.553191 (-1412 1784);
PAINT WHITE (-1412 1784);
WIRE 16 -1 (3600 3075)(1925 3075);
FORCEPROP 2 LAST SIG_NAME PU_CPU0_SOCKET_ID2
J 0
(2184 3084);
DISPLAY 0.680851 (2184 3084);
PAINT WHITE (2184 3084);
WIRE 16 -1 (3600 2675)(1925 2675);
FORCEPROP 2 LAST SIG_NAME PU_CPU0_SAFE_MODE_BOOT
J 0
(2184 2684);
DISPLAY 0.680851 (2184 2684);
PAINT WHITE (2184 2684);
WIRE 16 -1 (-525 2525)(-2200 2525);
FORCEPROP 2 LAST SIG_NAME NC_CLK_PFT_OUT_CPU0_DN
J 0
(-2137 2534);
DISPLAY 0.680851 (-2137 2534);
PAINT WHITE (-2137 2534);
WIRE 16 -1 (-525 2475)(-2200 2475);
FORCEPROP 2 LAST SIG_NAME NC_CLK_PFT_OUT_CPU0_DP
J 0
(-2137 2484);
DISPLAY 0.680851 (-2137 2484);
PAINT WHITE (-2137 2484);
WIRE 16 -1 (3600 2175)(1925 2175);
FORCEPROP 2 LAST SIG_NAME PD_EXT_CLK_SEL_CPU0
J 0
(2184 2184);
DISPLAY 0.680851 (2184 2184);
PAINT WHITE (2184 2184);
WIRE 16 -1 (-525 2825)(-2200 2825);
FORCEPROP 2 LAST SIG_NAME NC_XTAL_CPU0_25M_IN
J 0
(-2137 2834);
DISPLAY 0.680851 (-2137 2834);
PAINT WHITE (-2137 2834);
WIRE 16 -1 (-525 2625)(-2200 2625);
FORCEPROP 2 LAST SIG_NAME PUD_XTAL_CPU0_MODE1
J 0
(-2137 2634);
DISPLAY 0.680851 (-2137 2634);
PAINT WHITE (-2137 2634);
WIRE 16 -1 (3600 2875)(1925 2875);
FORCEPROP 2 LAST SIG_NAME FM_CPU0_PROC_ID0
J 0
(2184 2884);
DISPLAY 0.680851 (2184 2884);
PAINT WHITE (2184 2884);
WIRE 16 -1 (3600 2825)(1925 2825);
FORCEPROP 2 LAST SIG_NAME FM_CPU0_PROC_ID1
J 0
(2184 2834);
DISPLAY 0.680851 (2184 2834);
PAINT WHITE (2184 2834);
WIRE 16 -1 (3600 2725)(1925 2725);
FORCEPROP 2 LAST SIG_NAME TP_CPU0_PROCDIS_COD_GTL_N
J 0
(2184 2734);
DISPLAY 0.680851 (2184 2734);
PAINT WHITE (2184 2734);
WIRE 16 -1 (-525 2025)(-2025 2025);
FORCEPROP 2 LAST SIG_NAME H_CPU0_PREQ_QS_GTL_R_N
J 0
(-1412 2034);
DISPLAY 0.553191 (-1412 2034);
PAINT WHITE (-1412 2034);
WIRE 16 -1 (-525 2075)(-2025 2075);
FORCEPROP 2 LAST SIG_NAME H_CPU0_PRDY_QS_GTL_R_N
J 0
(-1412 2084);
DISPLAY 0.553191 (-1412 2084);
PAINT WHITE (-1412 2084);
WIRE 16 -1 (3600 3025)(1925 3025);
FORCEPROP 2 LAST SIG_NAME FM_CPU0_PKGID0
J 0
(2184 3034);
DISPLAY 0.680851 (2184 3034);
PAINT WHITE (2184 3034);
WIRE 16 -1 (3600 2975)(1925 2975);
FORCEPROP 2 LAST SIG_NAME FM_CPU0_PKGID1
J 0
(2184 2984);
DISPLAY 0.680851 (2184 2984);
PAINT WHITE (2184 2984);
WIRE 16 -1 (3600 2925)(1925 2925);
FORCEPROP 2 LAST SIG_NAME FM_CPU0_PKGID2
J 0
(2184 2934);
DISPLAY 0.680851 (2184 2934);
PAINT WHITE (2184 2934);
WIRE 16 -1 (-525 1925)(-2025 1925);
FORCEPROP 2 LAST SIG_NAME PECI_CPU0_GTL_R
J 0
(-1412 1934);
DISPLAY 0.553191 (-1412 1934);
PAINT WHITE (-1412 1934);
WIRE 16 -1 (3600 2075)(1925 2075);
FORCEPROP 2 LAST SIG_NAME TP_CPU0_BR23
J 0
(2184 2084);
DISPLAY 0.680851 (2184 2084);
PAINT WHITE (2184 2084);
WIRE 16 -1 (3600 3475)(1925 3475);
FORCEPROP 2 LAST SIG_NAME PU_CPU0_LEGACY_SKT
J 0
(2184 3484);
DISPLAY 0.680851 (2184 3484);
PAINT WHITE (2184 3484);
WIRE 16 -1 (3600 2275)(1925 2275);
FORCEPROP 2 LAST SIG_NAME RST_CPU0_DRAM_GH_N
J 0
(2184 2284);
DISPLAY 0.680851 (2184 2284);
PAINT WHITE (2184 2284);
WIRE 16 -1 (3600 2325)(1925 2325);
FORCEPROP 2 LAST SIG_NAME RST_CPU0_DRAM_EF_N
J 0
(2184 2334);
DISPLAY 0.680851 (2184 2334);
PAINT WHITE (2184 2334);
WIRE 16 -1 (-525 2175)(-2200 2175);
FORCEPROP 2 LAST SIG_NAME I3C_SPD_DDREFGH_CPU0_SDA
J 0
(-2137 2184);
DISPLAY 0.680851 (-2137 2184);
PAINT WHITE (-2137 2184);
WIRE 16 -1 (-525 2225)(-2200 2225);
FORCEPROP 2 LAST SIG_NAME I3C_SPD_DDREFGH_CPU0_SCL
J 0
(-2137 2234);
DISPLAY 0.680851 (-2137 2234);
PAINT WHITE (-2137 2234);
WIRE 16 -1 (3600 2375)(1925 2375);
FORCEPROP 2 LAST SIG_NAME RST_CPU0_DRAM_CD_N
J 0
(2184 2384);
DISPLAY 0.680851 (2184 2384);
PAINT WHITE (2184 2384);
WIRE 16 -1 (3600 2425)(1925 2425);
FORCEPROP 2 LAST SIG_NAME RST_CPU0_DRAM_AB_N
J 0
(2184 2434);
DISPLAY 0.680851 (2184 2434);
PAINT WHITE (2184 2434);
WIRE 16 -1 (-525 2325)(-2200 2325);
FORCEPROP 2 LAST SIG_NAME I3C_SPD_DDRABCD_CPU0_SDA
J 0
(-2137 2334);
DISPLAY 0.680851 (-2137 2334);
PAINT WHITE (-2137 2334);
WIRE 16 -1 (3600 3525)(1925 3525);
FORCEPROP 2 LAST SIG_NAME H_CPU0_BMCINIT_LVC1
J 0
(2184 3534);
DISPLAY 0.680851 (2184 3534);
PAINT WHITE (2184 3534);
WIRE 16 -1 (3600 3575)(1925 3575);
FORCEPROP 2 LAST SIG_NAME PD_CPU0_BIST_ENABLE
J 0
(2184 3583);
DISPLAY 0.680851 (2184 3583);
PAINT WHITE (2184 3583);
WIRE 16 -1 (-525 3125)(-2200 3125);
FORCEPROP 2 LAST SIG_NAME CLK_100M_DB2000_CPU0_BCLK3_DP
J 0
(-2137 3134);
DISPLAY 0.680851 (-2137 3134);
PAINT WHITE (-2137 3134);
WIRE 16 -1 (-525 3075)(-2200 3075);
FORCEPROP 2 LAST SIG_NAME CLK_100M_DB2000_CPU0_BCLK3_DN
J 0
(-2135 3083);
DISPLAY 0.680851 (-2135 3083);
PAINT WHITE (-2135 3083);
WIRE 16 -1 (-525 3275)(-2200 3275);
FORCEPROP 2 LAST SIG_NAME CLK_100M_DB2000_CPU0_BCLK2_DP
J 0
(-2137 3284);
DISPLAY 0.680851 (-2137 3284);
PAINT WHITE (-2137 3284);
WIRE 16 -1 (-525 3225)(-2200 3225);
FORCEPROP 2 LAST SIG_NAME CLK_100M_DB2000_CPU0_BCLK2_DN
J 0
(-2135 3233);
DISPLAY 0.680851 (-2135 3233);
PAINT WHITE (-2135 3233);
WIRE 16 -1 (-525 3575)(-2200 3575);
FORCEPROP 2 LAST SIG_NAME CLK_100M_DB2000_CPU0_BCLK0_DP
J 0
(-2141 3583);
DISPLAY 0.680851 (-2141 3583);
PAINT WHITE (-2141 3583);
WIRE 16 -1 (-525 3375)(-2200 3375);
FORCEPROP 2 LAST SIG_NAME CLK_100M_DB2000_CPU0_BCLK1_DN
J 0
(-2140 3382);
DISPLAY 0.680851 (-2140 3382);
PAINT WHITE (-2140 3382);
WIRE 16 -1 (-525 3425)(-2200 3425);
FORCEPROP 2 LAST SIG_NAME CLK_100M_DB2000_CPU0_BCLK1_DP
J 0
(-2139 3432);
DISPLAY 0.680851 (-2139 3432);
PAINT WHITE (-2139 3432);
WIRE 16 -1 (-525 3525)(-2200 3525);
FORCEPROP 2 LAST SIG_NAME CLK_100M_DB2000_CPU0_BCLK0_DN
J 0
(-2141 3534);
DISPLAY 0.680851 (-2141 3534);
PAINT WHITE (-2141 3534);
WIRE 16 -1 (-525 2675)(-2200 2675);
FORCEPROP 2 LAST SIG_NAME PUD_XTAL_CPU0_MODE0
J 0
(-2137 2684);
DISPLAY 0.680851 (-2137 2684);
PAINT WHITE (-2137 2684);
WIRE 16 -1 (-525 2775)(-2200 2775);
FORCEPROP 2 LAST SIG_NAME NC_XTAL_CPU0_25M_OUT
J 0
(-2137 2784);
DISPLAY 0.680851 (-2137 2784);
PAINT WHITE (-2137 2784);
WIRE 16 -1 (-525 2925)(-2200 2925);
FORCEPROP 2 LAST SIG_NAME CLK_25M_NSSC_CPU0_DN
J 0
(-2137 2934);
DISPLAY 0.680851 (-2137 2934);
PAINT WHITE (-2137 2934);
WIRE 16 -1 (-2225 1925)(-3200 1925);
FORCEPROP 2 LAST SIG_NAME PECI_CPU_GTL
J 0
(-3087 1934);
DISPLAY 0.553191 (-3087 1934);
PAINT WHITE (-3087 1934);
WIRE 16 -1 (-2225 1825)(-3200 1825);
FORCEPROP 2 LAST SIG_NAME JTAG_MUX_CPU0_GTL_TDI
J 0
(-3087 1834);
DISPLAY 0.553191 (-3087 1834);
PAINT WHITE (-3087 1834);
WIRE 16 -1 (-2225 2075)(-3200 2075);
FORCEPROP 2 LAST SIG_NAME H_CPU_PRDY_QS_GTL_N
J 0
(-3087 2084);
DISPLAY 0.553191 (-3087 2084);
PAINT WHITE (-3087 2084);
WIRE 16 -1 (-2225 2025)(-3200 2025);
FORCEPROP 2 LAST SIG_NAME H_CPU_PREQ_QS_GTL_N
J 0
(-3087 2034);
DISPLAY 0.553191 (-3087 2034);
PAINT WHITE (-3087 2034);
WIRE 16 -1 (-2225 1725)(-3200 1725);
FORCEPROP 2 LAST SIG_NAME JTAG_DBP_CPU_QS_GTL_TMS
J 0
(-3087 1734);
DISPLAY 0.553191 (-3087 1734);
PAINT WHITE (-3087 1734);
WIRE 16 -1 (-2225 1775)(-3200 1775);
FORCEPROP 2 LAST SIG_NAME JTAG_DBP_CPU_GTL_TCK
J 0
(-3087 1784);
DISPLAY 0.553191 (-3087 1784);
PAINT WHITE (-3087 1784);
QUIT
